#ISCELL
  mstr_misc dns *
  *
#ISCELL
  mstr_symbols cad_note *
  *
#ISCELL
  mstr_symbols design_note *
  *
#ISCELL
  mstr_symbols intel_corp_bpage *
  *
#ISCELL
  mstr_standard offpage *
  page241_i1
#CELL
  mstr_discrete res *
  page241_i11
#CELL
  mstr_discrete cap *
  page241_i12
#CELL
  mstr_discrete cap *
  page241_i14
#ISCELL
  mstr_symbols gnd *
  page241_i16
#CELL
  mstr_discrete res *
  page241_i18
#ISCELL
  mstr_symbols gnd *
  page241_i19
#CELL
  mstr_discrete cap *
  page241_i2
#CELL
  mstr_discrete cap *
  page241_i3
#CELL
  mstr_discrete cap *
  page241_i30
#ISCELL
  mstr_symbols gnd *
  page241_i31
#ISCELL
  mstr_symbols gnd *
  page241_i32
#CELL
  mstr_discrete res *
  page241_i37
#CELL
  mstr_discrete cap *
  page241_i39
#ISCELL
  mstr_symbols gnd *
  page241_i4
#ISCELL
  mstr_symbols gnd *
  page241_i40
#CELL
  mstr_discrete cap *
  page241_i41
#ISCELL
  mstr_symbols gnd *
  page241_i44
#CELL
  mstr_discrete cap *
  page241_i45
#ISCELL
  mstr_symbols gnd *
  page241_i46
#CELL
  mstr_discrete cap *
  page241_i47
#ISCELL
  mstr_standard offpage *
  page241_i48
#CELL
  mstr_discrete res *
  page241_i50
#CELL
  mstr_discrete res *
  page241_i51
#ISCELL
  mstr_symbols gnd *
  page241_i52
#CELL
  mstr_discrete cap *
  page241_i53
#CELL
  mstr_discrete res *
  page241_i54
#ISCELL
  mstr_symbols gnd *
  page241_i55
#CELL
  mstr_discrete cap *
  page241_i57
#CELL
  mstr_discrete res *
  page241_i58
#ISCELL
  mstr_symbols gnd *
  page241_i59
#CELL
  mstr_discrete cap *
  page241_i63
#ISCELL
  mstr_symbols gnd *
  page241_i64
#ISCELL
  mstr_symbols p5v_stby *
  page241_i69
#ISCELL
  mstr_symbols p12v_stby *
  page241_i71
#CELL
  mstr_discrete res *
  page241_i78
#CELL
  mstr_discrete capp *
  page241_i8
#CELL
  mstr_discrete ferrite *
  page241_i82
#CELL
  mstr_vreg tps54821 *
  page241_i83
#ISCELL
  mstr_symbols p5v_stby *
  page241_i85
#ISCELL
  mstr_symbols gnd *
  page241_i86
#CELL
  mstr_discrete res *
  page241_i89
#CELL
  mstr_discrete res *
  page241_i9
#CELL
  mstr_discrete inductor *
  page241_i90
#CELL
  mstr_discrete res *
  page241_i91
